(kicad_pcb
	(version 20260206)
	(generator "pcbnew")
	(generator_version "10.0")
	(general
		(thickness 1.6)
		(legacy_teardrops no)
	)
	(paper "A4")
	(title_block
		(title "baseboard — 13948-1b.1110WZS1818.brd")
		(comment 1 "Honey Badger (Wiwynn) / footprints 547-551 of 2523")
	)
	(layers
		(0 "F.Cu" signal "TOP")
		(4 "In1.Cu" signal "L2GND")
		(6 "In2.Cu" signal "L3")
		(8 "In3.Cu" signal "L4VCC")
		(10 "In4.Cu" signal "L5VCC")
		(12 "In5.Cu" signal "L6")
		(14 "In6.Cu" signal "L7GND")
		(2 "B.Cu" signal "BOTTOM")
		(9 "F.Adhes" user "F.Adhesive")
		(11 "B.Adhes" user "B.Adhesive")
		(13 "F.Paste" user "Package Geometry/Pastemask Top")
		(15 "B.Paste" user "Package Geometry/Pastemask Bottom")
		(5 "F.SilkS" user "Ref Des/Silkscreen Top")
		(7 "B.SilkS" user "Ref Des/Silkscreen Bottom")
		(1 "F.Mask" user "Board Geometry/Soldermask Top")
		(3 "B.Mask" user "Board Geometry/Soldermask Bottom")
		(17 "Dwgs.User" user "User.Drawings")
		(19 "Cmts.User" user "User.Comments")
		(21 "Eco1.User" user "User.Eco1")
		(23 "Eco2.User" user "User.Eco2")
		(25 "Edge.Cuts" user "Board Geometry/Outline")
		(27 "Margin" user)
		(31 "F.CrtYd" user "Package Geometry/Place Bound Top")
		(29 "B.CrtYd" user "Package Geometry/Place Bound Bottom")
		(35 "F.Fab" user "Ref Des/Assembly Top")
		(33 "B.Fab" user "Ref Des/Assembly Bottom")
	)
	(footprint ""
		(layer "F.Cu")
		(at 170.932348 -115.941856 180)
		(property "Reference" "PU12"
			(at 0 0 180)
			(layer "F.SilkS")
			(hide yes)
			(effects
				(font
					(size 1.27 1.27)
				)
			)
		)
		(property "Value" "TPS53355DQPR-GP"
			(at 4.7498 -5.6896 180)
			(unlocked yes)
			(layer "F.Fab")
			(hide yes)
			(effects
				(font
					(size 1.016 1.016)
					(thickness 0.1524)
				)
			)
		)
		(property "Device Type" "QFN22G6050-G6133H60"
			(at 4.7498 -7.2136 180)
			(unlocked yes)
			(layer "F.Fab")
			(hide yes)
			(effects
				(font
					(size 1.016 1.016)
					(thickness 0.1524)
				)
			)
		)
		(duplicate_pad_numbers_are_jumpers no)
		(fp_line
			(start 3.556 3.5179)
			(end 3.556 2.2479)
			(stroke
				(width 0.1524)
				(type default)
			)
			(layer "F.SilkS")
		)
		(fp_line
			(start 2.286 3.5179)
			(end 3.556 3.5179)
			(stroke
				(width 0.1524)
				(type default)
			)
			(layer "F.SilkS")
		)
		(fp_line
			(start 1.500124 3.262122)
			(end 1.500124 4.024122)
			(stroke
				(width 0.1524)
				(type default)
			)
			(layer "F.SilkS")
		)
		(fp_line
			(start 0.500126 -3.262122)
			(end 0.500126 -3.770122)
			(stroke
				(width 0.1524)
				(type default)
			)
			(layer "F.SilkS")
		)
		(fp_line
			(start -0.999998 3.262122)
			(end -0.999998 3.770122)
			(stroke
				(width 0.1524)
				(type default)
			)
			(layer "F.SilkS")
		)
		(fp_line
			(start -1.999996 -3.262122)
			(end -1.999996 -4.024122)
			(stroke
				(width 0.1524)
				(type default)
			)
			(layer "F.SilkS")
		)
		(fp_line
			(start -2.286 -3.5179)
			(end -3.556 -3.5179)
			(stroke
				(width 0.1524)
				(type default)
			)
			(layer "F.SilkS")
		)
		(fp_line
			(start -3.556 3.5179)
			(end -2.286 3.5179)
			(stroke
				(width 0.1524)
				(type default)
			)
			(layer "F.SilkS")
		)
		(fp_line
			(start -3.556 2.2479)
			(end -3.556 3.5179)
			(stroke
				(width 0.1524)
				(type default)
			)
			(layer "F.SilkS")
		)
		(fp_line
			(start -3.556 -3.5179)
			(end -3.556 -2.2479)
			(stroke
				(width 0.1524)
				(type default)
			)
			(layer "F.SilkS")
		)
		(fp_poly
			(pts
				(xy 3.556 -3.5179) (xy 2.5273 -3.5179) (xy 3.556 -2.4892)
			)
			(stroke
				(width 0)
				(type default)
			)
			(fill yes)
			(layer "F.SilkS")
		)
		(fp_rect
			(start -2.9972 2.5019)
			(end 2.9972 -2.5019)
			(stroke
				(width 0)
				(type default)
			)
			(fill no)
			(layer "F.CrtYd")
		)
		(fp_poly
			(pts
				(xy 3.556 -2.5019) (xy -2.9972 -2.5019) (xy -2.9972 2.5019) (xy 2.9972 2.5019) (xy 2.9972 -2.4892)
				(xy 3.556 -2.4892) (xy 3.556 3.5179) (xy -3.556 3.5179) (xy -3.556 -3.5179) (xy 3.556 -3.5179)
			)
			(stroke
				(width 0)
				(type default)
			)
			(fill no)
			(layer "F.CrtYd")
		)
		(fp_rect
			(start -3.556 3.5179)
			(end 3.556 -3.5179)
			(stroke
				(width 0)
				(type default)
			)
			(fill no)
			(layer "F.Fab")
		)
		(pad "1" smd rect
			(at 2.500122 -2.449322 180)
			(size 0.3048 1.1176)
			(layers "F.Cu" "F.Mask" "F.Paste")
			(net "P0V9_E_VFB")
		)
		(pad "2" smd rect
			(at 1.999996 -2.449322 180)
			(size 0.3048 1.1176)
			(layers "F.Cu" "F.Mask" "F.Paste")
			(net "P0V9_E_EN")
		)
		(pad "3" smd rect
			(at 1.500124 -2.449322 180)
			(size 0.3048 1.1176)
			(layers "F.Cu" "F.Mask" "F.Paste")
			(net "P0V9_E_PG")
		)
		(pad "4" smd rect
			(at 0.999998 -2.449322 180)
			(size 0.3048 1.1176)
			(layers "F.Cu" "F.Mask" "F.Paste")
			(net "P0V9_E_VBST")
		)
		(pad "5" smd rect
			(at 0.500126 -2.449322 180)
			(size 0.3048 1.1176)
			(layers "F.Cu" "F.Mask" "F.Paste")
			(net "Net_1134")
		)
		(pad "6" smd rect
			(at 0 -2.449322 180)
			(size 0.3048 1.1176)
			(layers "F.Cu" "F.Mask" "F.Paste")
			(net "P0V9_E_LX")
		)
		(pad "7" smd rect
			(at -0.500126 -2.449322 180)
			(size 0.3048 1.1176)
			(layers "F.Cu" "F.Mask" "F.Paste")
			(net "P0V9_E_LX")
		)
		(pad "8" smd rect
			(at -0.999998 -2.449322 180)
			(size 0.3048 1.1176)
			(layers "F.Cu" "F.Mask" "F.Paste")
			(net "P0V9_E_LX")
		)
		(pad "9" smd rect
			(at -1.500124 -2.449322 180)
			(size 0.3048 1.1176)
			(layers "F.Cu" "F.Mask" "F.Paste")
			(net "P0V9_E_LX")
		)
		(pad "10" smd rect
			(at -1.999996 -2.449322 180)
			(size 0.3048 1.1176)
			(layers "F.Cu" "F.Mask" "F.Paste")
			(net "P0V9_E_LX")
		)
		(pad "11" smd rect
			(at -2.500122 -2.449322 180)
			(size 0.3048 1.1176)
			(layers "F.Cu" "F.Mask" "F.Paste")
			(net "P0V9_E_LX")
		)
		(pad "12" smd rect
			(at -2.500122 2.449322 180)
			(size 0.3048 1.1176)
			(layers "F.Cu" "F.Mask" "F.Paste")
			(net "P0V9_E_VIN")
		)
		(pad "13" smd rect
			(at -1.999996 2.449322 180)
			(size 0.3048 1.1176)
			(layers "F.Cu" "F.Mask" "F.Paste")
			(net "P0V9_E_VIN")
		)
		(pad "14" smd rect
			(at -1.500124 2.449322 180)
			(size 0.3048 1.1176)
			(layers "F.Cu" "F.Mask" "F.Paste")
			(net "P0V9_E_VIN")
		)
		(pad "15" smd rect
			(at -0.999998 2.449322 180)
			(size 0.3048 1.1176)
			(layers "F.Cu" "F.Mask" "F.Paste")
			(net "P0V9_E_VIN")
		)
		(pad "16" smd rect
			(at -0.500126 2.449322 180)
			(size 0.3048 1.1176)
			(layers "F.Cu" "F.Mask" "F.Paste")
			(net "P0V9_E_VIN")
		)
		(pad "17" smd rect
			(at 0 2.449322 180)
			(size 0.3048 1.1176)
			(layers "F.Cu" "F.Mask" "F.Paste")
			(net "P0V9_E_VIN")
		)
		(pad "18" smd rect
			(at 0.500126 2.449322 180)
			(size 0.3048 1.1176)
			(layers "F.Cu" "F.Mask" "F.Paste")
			(net "P0V9_E_VREG")
		)
		(pad "19" smd rect
			(at 0.999998 2.449322 180)
			(size 0.3048 1.1176)
			(layers "F.Cu" "F.Mask" "F.Paste")
			(net "P0V9_E_VDD")
		)
		(pad "20" smd rect
			(at 1.500124 2.449322 180)
			(size 0.3048 1.1176)
			(layers "F.Cu" "F.Mask" "F.Paste")
			(net "P0V9_E_MODE")
		)
		(pad "21" smd rect
			(at 1.999996 2.449322 180)
			(size 0.3048 1.1176)
			(layers "F.Cu" "F.Mask" "F.Paste")
			(net "P0V9_E_TRIP")
		)
		(pad "22" smd rect
			(at 2.500122 2.449322 180)
			(size 0.3048 1.1176)
			(layers "F.Cu" "F.Mask" "F.Paste")
			(net "P0V9_E_RF")
		)
		(pad "23" smd custom
			(at 0 0 180)
			(size 0.83185 0.83185)
			(layers "F.Cu" "F.Mask" "F.Paste")
			(net "GND")
			(options
				(clearance outline)
				(anchor circle)
			)
			(primitives
				(gr_poly
					(pts
						(xy -2.7813 1.6637) (xy -2.7813 1.2954) (xy -3.048 1.2954) (xy -3.048 0.9525) (xy -2.7813 0.9525)
						(xy -2.7813 -0.9525) (xy -3.048 -0.9525) (xy -3.048 -1.2954) (xy -2.7813 -1.2954) (xy -2.7813 -1.6637)
						(xy 2.7813 -1.6637) (xy 2.7813 -1.2954) (xy 3.048 -1.2954) (xy 3.048 -0.9525) (xy 2.7813 -0.9525)
						(xy 2.7813 0.9525) (xy 3.048 0.9525) (xy 3.048 1.2954) (xy 2.7813 1.2954) (xy 2.7813 1.6637)
					)
					(width 0)
					(fill yes)
				)
			)
		)
	)
	(footprint ""
		(layer "F.Cu")
		(at 19.762216 -195.12788 180)
		(property "Reference" "R642"
			(at 0 0 180)
			(layer "F.SilkS")
			(hide yes)
			(effects
				(font
					(size 1.27 1.27)
				)
			)
		)
		(property "Value" "4K7R2F-GP"
			(at 0.064008 -3.993896 180)
			(unlocked yes)
			(layer "F.Fab")
			(hide yes)
			(effects
				(font
					(size 1.016 1.016)
					(thickness 0.1524)
				)
			)
		)
		(property "Device Type" "R402H16"
			(at 0.064008 -5.517896 180)
			(unlocked yes)
			(layer "F.Fab")
			(hide yes)
			(effects
				(font
					(size 1.016 1.016)
					(thickness 0.1524)
				)
			)
		)
		(duplicate_pad_numbers_are_jumpers no)
		(fp_line
			(start 0.508 -0.9398)
			(end -0.508 -0.9398)
			(stroke
				(width 0.1524)
				(type default)
			)
			(layer "F.SilkS")
		)
		(fp_line
			(start -0.508 -0.9398)
			(end -0.508 0.9398)
			(stroke
				(width 0.1524)
				(type default)
			)
			(layer "F.SilkS")
		)
		(fp_rect
			(start -0.508 0.9398)
			(end 0.508 -0.9398)
			(stroke
				(width 0)
				(type default)
			)
			(fill no)
			(layer "F.CrtYd")
		)
		(fp_rect
			(start -0.508 0.9398)
			(end 0.508 -0.9398)
			(stroke
				(width 0)
				(type default)
			)
			(fill no)
			(layer "F.Fab")
		)
		(pad "1" smd custom
			(at 0 -0.4445 180)
			(size 0.1397 0.1397)
			(layers "F.Cu" "F.Mask" "F.Paste")
			(net "IO_EXP_HDD_PRE_A1")
			(options
				(clearance outline)
				(anchor circle)
			)
			(primitives
				(gr_poly
					(pts
						(arc
							(start -0.1778 -0.2794)
							(mid -0.249642 -0.249642)
							(end -0.2794 -0.1778)
						)
						(arc
							(start -0.2794 0.1778)
							(mid -0.249642 0.249642)
							(end -0.1778 0.2794)
						)
						(arc
							(start 0.1778 0.2794)
							(mid 0.249642 0.249642)
							(end 0.2794 0.1778)
						)
						(arc
							(start 0.2794 -0.1778)
							(mid 0.249642 -0.249642)
							(end 0.1778 -0.2794)
						)
					)
					(width 0)
					(fill yes)
				)
			)
		)
		(pad "2" smd custom
			(at 0 0.4445 180)
			(size 0.1397 0.1397)
			(layers "F.Cu" "F.Mask" "F.Paste")
			(net "GND")
			(options
				(clearance outline)
				(anchor circle)
			)
			(primitives
				(gr_poly
					(pts
						(arc
							(start -0.1778 -0.2794)
							(mid -0.249642 -0.249642)
							(end -0.2794 -0.1778)
						)
						(arc
							(start -0.2794 0.1778)
							(mid -0.249642 0.249642)
							(end -0.1778 0.2794)
						)
						(arc
							(start 0.1778 0.2794)
							(mid 0.249642 0.249642)
							(end 0.2794 0.1778)
						)
						(arc
							(start 0.2794 -0.1778)
							(mid 0.249642 -0.249642)
							(end 0.1778 -0.2794)
						)
					)
					(width 0)
					(fill yes)
				)
			)
		)
	)
	(footprint ""
		(layer "F.Cu")
		(at 41.54297 -134.62 90)
		(property "Reference" "SR915"
			(at 0 0 90)
			(layer "F.SilkS")
			(hide yes)
			(effects
				(font
					(size 1.27 1.27)
				)
			)
		)
		(property "Value" "10KR2F-2-GP"
			(at 0.064008 -3.993896 90)
			(unlocked yes)
			(layer "F.Fab")
			(hide yes)
			(effects
				(font
					(size 1.016 1.016)
					(thickness 0.1524)
				)
			)
		)
		(property "Device Type" "R402H16"
			(at 0.064008 -5.517896 90)
			(unlocked yes)
			(layer "F.Fab")
			(hide yes)
			(effects
				(font
					(size 1.016 1.016)
					(thickness 0.1524)
				)
			)
		)
		(duplicate_pad_numbers_are_jumpers no)
		(fp_line
			(start 0.508 -0.9398)
			(end -0.508 -0.9398)
			(stroke
				(width 0.1524)
				(type default)
			)
			(layer "F.SilkS")
		)
		(fp_line
			(start -0.508 -0.9398)
			(end -0.508 0.9398)
			(stroke
				(width 0.1524)
				(type default)
			)
			(layer "F.SilkS")
		)
		(fp_rect
			(start -0.508 0.9398)
			(end 0.508 -0.9398)
			(stroke
				(width 0)
				(type default)
			)
			(fill no)
			(layer "F.CrtYd")
		)
		(fp_rect
			(start -0.508 0.9398)
			(end 0.508 -0.9398)
			(stroke
				(width 0)
				(type default)
			)
			(fill no)
			(layer "F.Fab")
		)
		(pad "1" smd custom
			(at 0 -0.4445 90)
			(size 0.1397 0.1397)
			(layers "F.Cu" "F.Mask" "F.Paste")
			(net "P3V3_STBY_R5")
			(options
				(clearance outline)
				(anchor circle)
			)
			(primitives
				(gr_poly
					(pts
						(arc
							(start -0.1778 -0.2794)
							(mid -0.249642 -0.249642)
							(end -0.2794 -0.1778)
						)
						(arc
							(start -0.2794 0.1778)
							(mid -0.249642 0.249642)
							(end -0.1778 0.2794)
						)
						(arc
							(start 0.1778 0.2794)
							(mid 0.249642 0.249642)
							(end 0.2794 0.1778)
						)
						(arc
							(start 0.2794 -0.1778)
							(mid 0.249642 -0.249642)
							(end 0.1778 -0.2794)
						)
					)
					(width 0)
					(fill yes)
				)
			)
		)
		(pad "2" smd custom
			(at 0 0.4445 90)
			(size 0.1397 0.1397)
			(layers "F.Cu" "F.Mask" "F.Paste")
			(net "P3V3_STBY_G5")
			(options
				(clearance outline)
				(anchor circle)
			)
			(primitives
				(gr_poly
					(pts
						(arc
							(start -0.1778 -0.2794)
							(mid -0.249642 -0.249642)
							(end -0.2794 -0.1778)
						)
						(arc
							(start -0.2794 0.1778)
							(mid -0.249642 0.249642)
							(end -0.1778 0.2794)
						)
						(arc
							(start 0.1778 0.2794)
							(mid 0.249642 0.249642)
							(end 0.2794 0.1778)
						)
						(arc
							(start 0.2794 -0.1778)
							(mid 0.249642 -0.249642)
							(end 0.1778 -0.2794)
						)
					)
					(width 0)
					(fill yes)
				)
			)
		)
	)
	(footprint ""
		(layer "F.Cu")
		(at 98.660966 -64.008)
		(property "Reference" "SU57"
			(at 0 0 0)
			(layer "F.SilkS")
			(hide yes)
			(effects
				(font
					(size 1.27 1.27)
				)
			)
		)
		(property "Value" "TPS3808G18DRVT-GP-U"
			(at -2.7813 -0.4572 0)
			(unlocked yes)
			(layer "F.Fab")
			(hide yes)
			(effects
				(font
					(size 1.016 1.016)
					(thickness 0.1524)
				)
			)
		)
		(property "Device Type" "DFN6F2-G1711-UH32"
			(at -2.7813 -1.9812 0)
			(unlocked yes)
			(layer "F.Fab")
			(hide yes)
			(effects
				(font
					(size 1.016 1.016)
					(thickness 0.1524)
				)
			)
		)
		(duplicate_pad_numbers_are_jumpers no)
		(fp_line
			(start -1.5113 -1.7653)
			(end -0.7493 -1.7653)
			(stroke
				(width 0.1524)
				(type default)
			)
			(layer "F.SilkS")
		)
		(fp_line
			(start -1.5113 -1.0033)
			(end -1.5113 -1.7653)
			(stroke
				(width 0.1524)
				(type default)
			)
			(layer "F.SilkS")
		)
		(fp_line
			(start -1.5113 1.0033)
			(end -1.5113 1.7653)
			(stroke
				(width 0.1524)
				(type default)
			)
			(layer "F.SilkS")
		)
		(fp_line
			(start -1.5113 1.7653)
			(end -0.7493 1.7653)
			(stroke
				(width 0.1524)
				(type default)
			)
			(layer "F.SilkS")
		)
		(fp_line
			(start 0 1.5113)
			(end 0 2.0193)
			(stroke
				(width 0.1524)
				(type default)
			)
			(layer "F.SilkS")
		)
		(fp_line
			(start 1.5113 1.0033)
			(end 1.5113 1.7653)
			(stroke
				(width 0.1524)
				(type default)
			)
			(layer "F.SilkS")
		)
		(fp_line
			(start 1.5113 1.7653)
			(end 0.7493 1.7653)
			(stroke
				(width 0.1524)
				(type default)
			)
			(layer "F.SilkS")
		)
		(fp_poly
			(pts
				(xy 0.7493 -1.7653) (xy 1.5113 -1.0033) (xy 1.5113 -1.7653)
			)
			(stroke
				(width 0)
				(type default)
			)
			(fill yes)
			(layer "F.SilkS")
		)
		(fp_rect
			(start -1.0033 1.0033)
			(end 1.0033 -1.0033)
			(stroke
				(width 0)
				(type default)
			)
			(fill no)
			(layer "F.CrtYd")
		)
		(fp_poly
			(pts
				(xy -1.5113 1.7653) (xy -1.5113 -1.7653) (xy 1.5113 -1.7653) (xy 1.5113 0.99822) (xy 1.0033 0.99822)
				(xy 1.0033 -1.0033) (xy -1.0033 -1.0033) (xy -1.0033 1.0033) (xy 1.5113 1.0033) (xy 1.5113 1.7653)
			)
			(stroke
				(width 0)
				(type default)
			)
			(fill no)
			(layer "F.CrtYd")
		)
		(fp_rect
			(start -1.5113 1.7653)
			(end 1.5113 -1.7653)
			(stroke
				(width 0)
				(type default)
			)
			(fill no)
			(layer "F.Fab")
		)
		(pad "1" smd rect
			(at 0.649986 -1.1303)
			(size 0.4064 0.508)
			(drill
				(offset 0 0.127)
			)
			(layers "F.Cu" "F.Mask" "F.Paste")
			(net "P1V8_STBY")
		)
		(pad "2" smd rect
			(at 0 -1.1303)
			(size 0.4064 0.508)
			(drill
				(offset 0 0.127)
			)
			(layers "F.Cu" "F.Mask" "F.Paste")
			(net "PWRGD_P0V955_C")
		)
		(pad "3" smd rect
			(at -0.649986 -1.1303)
			(size 0.4064 0.508)
			(drill
				(offset 0 0.127)
			)
			(layers "F.Cu" "F.Mask" "F.Paste")
			(net "Net_8")
		)
		(pad "4" smd rect
			(at -0.649986 1.1303)
			(size 0.4064 0.508)
			(drill
				(offset 0 -0.127)
			)
			(layers "F.Cu" "F.Mask" "F.Paste")
			(net "IOC_VREF_SET")
		)
		(pad "5" smd rect
			(at 0 1.1303)
			(size 0.4064 0.508)
			(drill
				(offset 0 -0.127)
			)
			(layers "F.Cu" "F.Mask" "F.Paste")
			(net "GND")
		)
		(pad "6" smd rect
			(at 0.649986 1.1303)
			(size 0.4064 0.508)
			(drill
				(offset 0 -0.127)
			)
			(layers "F.Cu" "F.Mask" "F.Paste")
			(net "IOC_RESET#")
		)
		(pad "7" smd rect
			(at 0 0)
			(size 1.7018 1.0922)
			(layers "F.Cu" "F.Mask" "F.Paste")
			(net "GND")
		)
	)
	(footprint ""
		(layer "F.Cu")
		(at 191.516 -146.177 -90)
		(property "Reference" "SR738"
			(at 0 0 270)
			(layer "F.SilkS")
			(hide yes)
			(effects
				(font
					(size 1.27 1.27)
				)
			)
		)
		(property "Value" "2K2R2F-GP"
			(at 0.064008 -3.993896 270)
			(unlocked yes)
			(layer "F.Fab")
			(hide yes)
			(effects
				(font
					(size 1.016 1.016)
					(thickness 0.1524)
				)
			)
		)
		(property "Device Type" "R402H16"
			(at 0.064008 -5.517896 270)
			(unlocked yes)
			(layer "F.Fab")
			(hide yes)
			(effects
				(font
					(size 1.016 1.016)
					(thickness 0.1524)
				)
			)
		)
		(duplicate_pad_numbers_are_jumpers no)
		(fp_line
			(start -0.508 -0.9398)
			(end -0.508 0.9398)
			(stroke
				(width 0.1524)
				(type default)
			)
			(layer "F.SilkS")
		)
		(fp_line
			(start 0.508 -0.9398)
			(end -0.508 -0.9398)
			(stroke
				(width 0.1524)
				(type default)
			)
			(layer "F.SilkS")
		)
		(fp_rect
			(start -0.508 0.9398)
			(end 0.508 -0.9398)
			(stroke
				(width 0)
				(type default)
			)
			(fill no)
			(layer "F.CrtYd")
		)
		(fp_rect
			(start -0.508 0.9398)
			(end 0.508 -0.9398)
			(stroke
				(width 0)
				(type default)
			)
			(fill no)
			(layer "F.Fab")
		)
		(pad "1" smd custom
			(at 0 -0.4445 270)
			(size 0.1397 0.1397)
			(layers "F.Cu" "F.Mask" "F.Paste")
			(net "EXP_I2C_SCL_3")
			(options
				(clearance outline)
				(anchor circle)
			)
			(primitives
				(gr_poly
					(pts
						(arc
							(start -0.1778 -0.2794)
							(mid -0.249642 -0.249642)
							(end -0.2794 -0.1778)
						)
						(arc
							(start -0.2794 0.1778)
							(mid -0.249642 0.249642)
							(end -0.1778 0.2794)
						)
						(arc
							(start 0.1778 0.2794)
							(mid 0.249642 0.249642)
							(end 0.2794 0.1778)
						)
						(arc
							(start 0.2794 -0.1778)
							(mid 0.249642 -0.249642)
							(end 0.1778 -0.2794)
						)
					)
					(width 0)
					(fill yes)
				)
			)
		)
		(pad "2" smd custom
			(at 0 0.4445 270)
			(size 0.1397 0.1397)
			(layers "F.Cu" "F.Mask" "F.Paste")
			(net "P1V8_E")
			(options
				(clearance outline)
				(anchor circle)
			)
			(primitives
				(gr_poly
					(pts
						(arc
							(start -0.1778 -0.2794)
							(mid -0.249642 -0.249642)
							(end -0.2794 -0.1778)
						)
						(arc
							(start -0.2794 0.1778)
							(mid -0.249642 0.249642)
							(end -0.1778 0.2794)
						)
						(arc
							(start 0.1778 0.2794)
							(mid 0.249642 0.249642)
							(end 0.2794 0.1778)
						)
						(arc
							(start 0.2794 -0.1778)
							(mid 0.249642 -0.249642)
							(end 0.1778 -0.2794)
						)
					)
					(width 0)
					(fill yes)
				)
			)
		)
	)
)
